(kicad_pcb
	(version 20260206)
	(generator "pcbnew")
	(generator_version "10.0")
	(general
		(thickness 1.6)
		(legacy_teardrops no)
	)
	(paper "A4")
	(title_block
		(title "03242023_DA0F0TMBIJ0_F0T_Motherboard_J_brd_V01_OCP.brd")
		(comment 1 "Grand Teton / footprints 6085-6091 of 6105")
	)
	(layers
		(0 "F.Cu" signal "TOP")
		(4 "In1.Cu" signal "GND")
		(6 "In2.Cu" signal "IN1")
		(8 "In3.Cu" signal "GND1")
		(10 "In4.Cu" signal "IN2")
		(12 "In5.Cu" signal "GND2")
		(14 "In6.Cu" signal "IN3")
		(16 "In7.Cu" signal "GND3")
		(18 "In8.Cu" signal "VCC")
		(20 "In9.Cu" signal "VCC1")
		(22 "In10.Cu" signal "GND4")
		(24 "In11.Cu" signal "IN4")
		(26 "In12.Cu" signal "GND5")
		(28 "In13.Cu" signal "IN5")
		(30 "In14.Cu" signal "GND6")
		(32 "In15.Cu" signal "IN6")
		(34 "In16.Cu" signal "GND7")
		(2 "B.Cu" signal "BOTTOM")
		(9 "F.Adhes" user "F.Adhesive")
		(11 "B.Adhes" user "B.Adhesive")
		(13 "F.Paste" user "Package Geometry/Pastemask Top")
		(15 "B.Paste" user "Package Geometry/Pastemask Bottom")
		(5 "F.SilkS" user "Ref Des/Silkscreen Top")
		(7 "B.SilkS" user "Ref Des/Silkscreen Bottom")
		(1 "F.Mask" user "Board Geometry/Soldermask Top")
		(3 "B.Mask" user "Board Geometry/Soldermask Bottom")
		(17 "Dwgs.User" user "User.Drawings")
		(19 "Cmts.User" user "User.Comments")
		(21 "Eco1.User" user "User.Eco1")
		(23 "Eco2.User" user "User.Eco2")
		(25 "Edge.Cuts" user "Board Geometry/Outline")
		(27 "Margin" user)
		(31 "F.CrtYd" user "Package Geometry/Place Bound Top")
		(29 "B.CrtYd" user "Package Geometry/Place Bound Bottom")
		(35 "F.Fab" user "Ref Des/Assembly Top")
		(33 "B.Fab" user "Ref Des/Assembly Bottom")
	)
	(footprint ""
		(layer "B.Cu")
		(at 453.34174 -71.244968 90)
		(property "Reference" "PC71"
			(at 0 0 90)
			(layer "B.SilkS")
			(hide yes)
			(effects
				(font
					(size 1.27 1.27)
				)
				(justify mirror)
			)
		)
		(property "Value" ""
			(at 0 0 90)
			(layer "B.Fab")
			(effects
				(font
					(size 1.27 1.27)
				)
				(justify mirror)
			)
		)
		(duplicate_pad_numbers_are_jumpers no)
		(fp_line
			(start 1.524 -0.762)
			(end -1.524 -0.762)
			(stroke
				(width 0.1524)
				(type default)
			)
			(layer "B.SilkS")
		)
		(fp_line
			(start -1.524 -0.762)
			(end -1.524 0.762)
			(stroke
				(width 0.1524)
				(type default)
			)
			(layer "B.SilkS")
		)
		(fp_line
			(start 1.524 0.762)
			(end 1.524 -0.762)
			(stroke
				(width 0.1524)
				(type default)
			)
			(layer "B.SilkS")
		)
		(fp_line
			(start -1.524 0.762)
			(end 1.524 0.762)
			(stroke
				(width 0.1524)
				(type default)
			)
			(layer "B.SilkS")
		)
		(fp_line
			(start 1.1049 -0.724916)
			(end 1.1049 0.724916)
			(stroke
				(width 0.1)
				(type default)
			)
			(layer "B.Fab")
		)
		(fp_line
			(start -1.1049 -0.724916)
			(end 1.1049 -0.724916)
			(stroke
				(width 0.1)
				(type default)
			)
			(layer "B.Fab")
		)
		(fp_line
			(start 1.1049 0.724916)
			(end -1.1049 0.724916)
			(stroke
				(width 0.1)
				(type default)
			)
			(layer "B.Fab")
		)
		(fp_line
			(start -1.1049 0.724916)
			(end -1.1049 -0.724916)
			(stroke
				(width 0.1)
				(type default)
			)
			(layer "B.Fab")
		)
		(pad "1" smd rect
			(at 0.889 0 90)
			(size 1.016 1.27)
			(layers "B.Cu" "B.Mask" "B.Paste")
			(net "SW_P3V3_AUX_FLT")
		)
		(pad "2" smd rect
			(at -0.889 0 90)
			(size 1.016 1.27)
			(layers "B.Cu" "B.Mask" "B.Paste")
			(net "GND")
		)
	)
	(footprint ""
		(layer "B.Cu")
		(at 368.075972 -184.400952 90)
		(property "Reference" "R967"
			(at 0 0 90)
			(layer "B.SilkS")
			(hide yes)
			(effects
				(font
					(size 1.27 1.27)
				)
				(justify mirror)
			)
		)
		(property "Value" ""
			(at 0 0 90)
			(layer "B.Fab")
			(effects
				(font
					(size 1.27 1.27)
				)
				(justify mirror)
			)
		)
		(duplicate_pad_numbers_are_jumpers no)
		(fp_line
			(start 0.7874 -0.4064)
			(end -0.7874 -0.4064)
			(stroke
				(width 0.1524)
				(type default)
			)
			(layer "B.SilkS")
		)
		(fp_line
			(start -0.7874 -0.4064)
			(end -0.7874 0.4064)
			(stroke
				(width 0.1524)
				(type default)
			)
			(layer "B.SilkS")
		)
		(fp_line
			(start 0.7874 0.4064)
			(end 0.7874 -0.4064)
			(stroke
				(width 0.1524)
				(type default)
			)
			(layer "B.SilkS")
		)
		(fp_line
			(start -0.7874 0.4064)
			(end 0.7874 0.4064)
			(stroke
				(width 0.1524)
				(type default)
			)
			(layer "B.SilkS")
		)
		(fp_line
			(start 0.67945 -0.305054)
			(end 0.12065 -0.305054)
			(stroke
				(width 0.1)
				(type default)
			)
			(layer "B.Fab")
		)
		(fp_line
			(start 0.12065 -0.305054)
			(end 0.12065 -0.2794)
			(stroke
				(width 0.1)
				(type default)
			)
			(layer "B.Fab")
		)
		(fp_line
			(start -0.12065 -0.3048)
			(end -0.67945 -0.3048)
			(stroke
				(width 0.1)
				(type default)
			)
			(layer "B.Fab")
		)
		(fp_line
			(start -0.67945 -0.3048)
			(end -0.67945 0.3048)
			(stroke
				(width 0.1)
				(type default)
			)
			(layer "B.Fab")
		)
		(fp_line
			(start 0.12065 -0.2794)
			(end -0.12065 -0.2794)
			(stroke
				(width 0.1)
				(type default)
			)
			(layer "B.Fab")
		)
		(fp_line
			(start -0.12065 -0.2794)
			(end -0.12065 -0.3048)
			(stroke
				(width 0.1)
				(type default)
			)
			(layer "B.Fab")
		)
		(fp_line
			(start 0.12065 0.2794)
			(end 0.12065 0.3048)
			(stroke
				(width 0.1)
				(type default)
			)
			(layer "B.Fab")
		)
		(fp_line
			(start -0.120396 0.2794)
			(end 0.12065 0.2794)
			(stroke
				(width 0.1)
				(type default)
			)
			(layer "B.Fab")
		)
		(fp_line
			(start 0.67945 0.3048)
			(end 0.67945 -0.305054)
			(stroke
				(width 0.1)
				(type default)
			)
			(layer "B.Fab")
		)
		(fp_line
			(start 0.12065 0.3048)
			(end 0.67945 0.3048)
			(stroke
				(width 0.1)
				(type default)
			)
			(layer "B.Fab")
		)
		(fp_line
			(start -0.120396 0.3048)
			(end -0.120396 0.2794)
			(stroke
				(width 0.1)
				(type default)
			)
			(layer "B.Fab")
		)
		(fp_line
			(start -0.67945 0.3048)
			(end -0.120396 0.3048)
			(stroke
				(width 0.1)
				(type default)
			)
			(layer "B.Fab")
		)
		(pad "1" smd circle
			(at 0.40005 0 270)
			(size 0 0)
			(layers "B.Cu" "B.Mask" "B.Paste")
			(net "P3V3_AUX")
		)
		(pad "2" smd circle
			(at -0.40005 0 270)
			(size 0 0)
			(layers "B.Cu" "B.Mask" "B.Paste")
			(net "SMB_PEHPCPU0_LVC3_SDA")
		)
	)
	(footprint ""
		(layer "B.Cu")
		(at 339.27669 -47.512986 180)
		(property "Reference" "C1228"
			(at 0 0 0)
			(layer "B.SilkS")
			(hide yes)
			(effects
				(font
					(size 1.27 1.27)
				)
				(justify mirror)
			)
		)
		(property "Value" ""
			(at 0 0 0)
			(layer "B.Fab")
			(effects
				(font
					(size 1.27 1.27)
				)
				(justify mirror)
			)
		)
		(duplicate_pad_numbers_are_jumpers no)
		(fp_line
			(start 0.7874 0.4064)
			(end 0.7874 -0.4064)
			(stroke
				(width 0.1524)
				(type default)
			)
			(layer "B.SilkS")
		)
		(fp_line
			(start 0.7874 -0.4064)
			(end -0.7874 -0.4064)
			(stroke
				(width 0.1524)
				(type default)
			)
			(layer "B.SilkS")
		)
		(fp_line
			(start -0.7874 0.4064)
			(end 0.7874 0.4064)
			(stroke
				(width 0.1524)
				(type default)
			)
			(layer "B.SilkS")
		)
		(fp_line
			(start -0.7874 -0.4064)
			(end -0.7874 0.4064)
			(stroke
				(width 0.1524)
				(type default)
			)
			(layer "B.SilkS")
		)
		(fp_line
			(start 0.67945 0.3048)
			(end 0.67945 -0.305054)
			(stroke
				(width 0.1)
				(type default)
			)
			(layer "B.Fab")
		)
		(fp_line
			(start 0.67945 -0.305054)
			(end 0.12065 -0.305054)
			(stroke
				(width 0.1)
				(type default)
			)
			(layer "B.Fab")
		)
		(fp_line
			(start 0.12065 0.3048)
			(end 0.67945 0.3048)
			(stroke
				(width 0.1)
				(type default)
			)
			(layer "B.Fab")
		)
		(fp_line
			(start 0.12065 0.2794)
			(end 0.12065 0.3048)
			(stroke
				(width 0.1)
				(type default)
			)
			(layer "B.Fab")
		)
		(fp_line
			(start 0.12065 -0.2794)
			(end -0.12065 -0.2794)
			(stroke
				(width 0.1)
				(type default)
			)
			(layer "B.Fab")
		)
		(fp_line
			(start 0.12065 -0.305054)
			(end 0.12065 -0.2794)
			(stroke
				(width 0.1)
				(type default)
			)
			(layer "B.Fab")
		)
		(fp_line
			(start -0.120396 0.3048)
			(end -0.120396 0.2794)
			(stroke
				(width 0.1)
				(type default)
			)
			(layer "B.Fab")
		)
		(fp_line
			(start -0.120396 0.2794)
			(end 0.12065 0.2794)
			(stroke
				(width 0.1)
				(type default)
			)
			(layer "B.Fab")
		)
		(fp_line
			(start -0.12065 -0.2794)
			(end -0.12065 -0.3048)
			(stroke
				(width 0.1)
				(type default)
			)
			(layer "B.Fab")
		)
		(fp_line
			(start -0.12065 -0.3048)
			(end -0.67945 -0.3048)
			(stroke
				(width 0.1)
				(type default)
			)
			(layer "B.Fab")
		)
		(fp_line
			(start -0.67945 0.3048)
			(end -0.120396 0.3048)
			(stroke
				(width 0.1)
				(type default)
			)
			(layer "B.Fab")
		)
		(fp_line
			(start -0.67945 -0.3048)
			(end -0.67945 0.3048)
			(stroke
				(width 0.1)
				(type default)
			)
			(layer "B.Fab")
		)
		(pad "1" smd circle
			(at 0.40005 0)
			(size 0 0)
			(layers "B.Cu" "B.Mask" "B.Paste")
			(net "P1V05_PCH_AUX")
		)
		(pad "2" smd circle
			(at -0.40005 0)
			(size 0 0)
			(layers "B.Cu" "B.Mask" "B.Paste")
			(net "GND")
		)
	)
	(footprint ""
		(layer "B.Cu")
		(at 374.002046 -328.298048 -90)
		(property "Reference" "PC267_P0_5"
			(at 0 0 90)
			(layer "B.SilkS")
			(hide yes)
			(effects
				(font
					(size 1.27 1.27)
				)
				(justify mirror)
			)
		)
		(property "Value" ""
			(at 0 0 90)
			(layer "B.Fab")
			(effects
				(font
					(size 1.27 1.27)
				)
				(justify mirror)
			)
		)
		(duplicate_pad_numbers_are_jumpers no)
		(fp_line
			(start -1.524 0.762)
			(end 1.524 0.762)
			(stroke
				(width 0.1524)
				(type default)
			)
			(layer "B.SilkS")
		)
		(fp_line
			(start 1.524 0.762)
			(end 1.524 -0.762)
			(stroke
				(width 0.1524)
				(type default)
			)
			(layer "B.SilkS")
		)
		(fp_line
			(start -1.524 -0.762)
			(end -1.524 0.762)
			(stroke
				(width 0.1524)
				(type default)
			)
			(layer "B.SilkS")
		)
		(fp_line
			(start 1.524 -0.762)
			(end -1.524 -0.762)
			(stroke
				(width 0.1524)
				(type default)
			)
			(layer "B.SilkS")
		)
		(fp_line
			(start -1.1049 0.724916)
			(end -1.1049 -0.724916)
			(stroke
				(width 0.1)
				(type default)
			)
			(layer "B.Fab")
		)
		(fp_line
			(start 1.1049 0.724916)
			(end -1.1049 0.724916)
			(stroke
				(width 0.1)
				(type default)
			)
			(layer "B.Fab")
		)
		(fp_line
			(start -1.1049 -0.724916)
			(end 1.1049 -0.724916)
			(stroke
				(width 0.1)
				(type default)
			)
			(layer "B.Fab")
		)
		(fp_line
			(start 1.1049 -0.724916)
			(end 1.1049 0.724916)
			(stroke
				(width 0.1)
				(type default)
			)
			(layer "B.Fab")
		)
		(pad "1" smd rect
			(at 0.889 0 270)
			(size 1.016 1.27)
			(layers "B.Cu" "B.Mask" "B.Paste")
			(net "PVCCIN_CPU0")
		)
		(pad "2" smd rect
			(at -0.889 0 270)
			(size 1.016 1.27)
			(layers "B.Cu" "B.Mask" "B.Paste")
			(net "GND")
		)
	)
	(footprint ""
		(layer "B.Cu")
		(at 343.8779 -35.222688 -90)
		(property "Reference" "R3938"
			(at 0 0 90)
			(layer "B.SilkS")
			(hide yes)
			(effects
				(font
					(size 1.27 1.27)
				)
				(justify mirror)
			)
		)
		(property "Value" ""
			(at 0 0 90)
			(layer "B.Fab")
			(effects
				(font
					(size 1.27 1.27)
				)
				(justify mirror)
			)
		)
		(duplicate_pad_numbers_are_jumpers no)
		(fp_line
			(start -0.7874 0.4064)
			(end 0.7874 0.4064)
			(stroke
				(width 0.1524)
				(type default)
			)
			(layer "B.SilkS")
		)
		(fp_line
			(start 0.7874 0.4064)
			(end 0.7874 -0.4064)
			(stroke
				(width 0.1524)
				(type default)
			)
			(layer "B.SilkS")
		)
		(fp_line
			(start -0.7874 -0.4064)
			(end -0.7874 0.4064)
			(stroke
				(width 0.1524)
				(type default)
			)
			(layer "B.SilkS")
		)
		(fp_line
			(start 0.7874 -0.4064)
			(end -0.7874 -0.4064)
			(stroke
				(width 0.1524)
				(type default)
			)
			(layer "B.SilkS")
		)
		(fp_line
			(start -0.67945 0.3048)
			(end -0.120396 0.3048)
			(stroke
				(width 0.1)
				(type default)
			)
			(layer "B.Fab")
		)
		(fp_line
			(start -0.120396 0.3048)
			(end -0.120396 0.2794)
			(stroke
				(width 0.1)
				(type default)
			)
			(layer "B.Fab")
		)
		(fp_line
			(start 0.12065 0.3048)
			(end 0.67945 0.3048)
			(stroke
				(width 0.1)
				(type default)
			)
			(layer "B.Fab")
		)
		(fp_line
			(start 0.67945 0.3048)
			(end 0.67945 -0.305054)
			(stroke
				(width 0.1)
				(type default)
			)
			(layer "B.Fab")
		)
		(fp_line
			(start -0.120396 0.2794)
			(end 0.12065 0.2794)
			(stroke
				(width 0.1)
				(type default)
			)
			(layer "B.Fab")
		)
		(fp_line
			(start 0.12065 0.2794)
			(end 0.12065 0.3048)
			(stroke
				(width 0.1)
				(type default)
			)
			(layer "B.Fab")
		)
		(fp_line
			(start -0.12065 -0.2794)
			(end -0.12065 -0.3048)
			(stroke
				(width 0.1)
				(type default)
			)
			(layer "B.Fab")
		)
		(fp_line
			(start 0.12065 -0.2794)
			(end -0.12065 -0.2794)
			(stroke
				(width 0.1)
				(type default)
			)
			(layer "B.Fab")
		)
		(fp_line
			(start -0.67945 -0.3048)
			(end -0.67945 0.3048)
			(stroke
				(width 0.1)
				(type default)
			)
			(layer "B.Fab")
		)
		(fp_line
			(start -0.12065 -0.3048)
			(end -0.67945 -0.3048)
			(stroke
				(width 0.1)
				(type default)
			)
			(layer "B.Fab")
		)
		(fp_line
			(start 0.12065 -0.305054)
			(end 0.12065 -0.2794)
			(stroke
				(width 0.1)
				(type default)
			)
			(layer "B.Fab")
		)
		(fp_line
			(start 0.67945 -0.305054)
			(end 0.12065 -0.305054)
			(stroke
				(width 0.1)
				(type default)
			)
			(layer "B.Fab")
		)
		(pad "1" smd circle
			(at 0.40005 0 90)
			(size 0 0)
			(layers "B.Cu" "B.Mask" "B.Paste")
			(net "PU_OC2_USB_N")
		)
		(pad "2" smd circle
			(at -0.40005 0 90)
			(size 0 0)
			(layers "B.Cu" "B.Mask" "B.Paste")
			(net "P3V3_AUX")
		)
	)
	(footprint ""
		(layer "B.Cu")
		(at 149.278848 -188.21019)
		(property "Reference" "R289"
			(at 0 0 0)
			(layer "B.SilkS")
			(hide yes)
			(effects
				(font
					(size 1.27 1.27)
				)
				(justify mirror)
			)
		)
		(property "Value" ""
			(at 0 0 0)
			(layer "B.Fab")
			(effects
				(font
					(size 1.27 1.27)
				)
				(justify mirror)
			)
		)
		(duplicate_pad_numbers_are_jumpers no)
		(fp_line
			(start -0.7874 -0.4064)
			(end -0.7874 0.4064)
			(stroke
				(width 0.1524)
				(type default)
			)
			(layer "B.SilkS")
		)
		(fp_line
			(start -0.7874 0.4064)
			(end 0.7874 0.4064)
			(stroke
				(width 0.1524)
				(type default)
			)
			(layer "B.SilkS")
		)
		(fp_line
			(start 0.7874 -0.4064)
			(end -0.7874 -0.4064)
			(stroke
				(width 0.1524)
				(type default)
			)
			(layer "B.SilkS")
		)
		(fp_line
			(start 0.7874 0.4064)
			(end 0.7874 -0.4064)
			(stroke
				(width 0.1524)
				(type default)
			)
			(layer "B.SilkS")
		)
		(fp_line
			(start -0.67945 -0.3048)
			(end -0.67945 0.3048)
			(stroke
				(width 0.1)
				(type default)
			)
			(layer "B.Fab")
		)
		(fp_line
			(start -0.67945 0.3048)
			(end -0.120396 0.3048)
			(stroke
				(width 0.1)
				(type default)
			)
			(layer "B.Fab")
		)
		(fp_line
			(start -0.12065 -0.3048)
			(end -0.67945 -0.3048)
			(stroke
				(width 0.1)
				(type default)
			)
			(layer "B.Fab")
		)
		(fp_line
			(start -0.12065 -0.2794)
			(end -0.12065 -0.3048)
			(stroke
				(width 0.1)
				(type default)
			)
			(layer "B.Fab")
		)
		(fp_line
			(start -0.120396 0.2794)
			(end 0.12065 0.2794)
			(stroke
				(width 0.1)
				(type default)
			)
			(layer "B.Fab")
		)
		(fp_line
			(start -0.120396 0.3048)
			(end -0.120396 0.2794)
			(stroke
				(width 0.1)
				(type default)
			)
			(layer "B.Fab")
		)
		(fp_line
			(start 0.12065 -0.305054)
			(end 0.12065 -0.2794)
			(stroke
				(width 0.1)
				(type default)
			)
			(layer "B.Fab")
		)
		(fp_line
			(start 0.12065 -0.2794)
			(end -0.12065 -0.2794)
			(stroke
				(width 0.1)
				(type default)
			)
			(layer "B.Fab")
		)
		(fp_line
			(start 0.12065 0.2794)
			(end 0.12065 0.3048)
			(stroke
				(width 0.1)
				(type default)
			)
			(layer "B.Fab")
		)
		(fp_line
			(start 0.12065 0.3048)
			(end 0.67945 0.3048)
			(stroke
				(width 0.1)
				(type default)
			)
			(layer "B.Fab")
		)
		(fp_line
			(start 0.67945 -0.305054)
			(end 0.12065 -0.305054)
			(stroke
				(width 0.1)
				(type default)
			)
			(layer "B.Fab")
		)
		(fp_line
			(start 0.67945 0.3048)
			(end 0.67945 -0.305054)
			(stroke
				(width 0.1)
				(type default)
			)
			(layer "B.Fab")
		)
		(pad "1" smd circle
			(at 0.40005 0 180)
			(size 0 0)
			(layers "B.Cu" "B.Mask" "B.Paste")
			(net "PD_CPU1_TXT_PLTEN")
		)
		(pad "2" smd circle
			(at -0.40005 0 180)
			(size 0 0)
			(layers "B.Cu" "B.Mask" "B.Paste")
			(net "GND")
		)
	)
	(footprint ""
		(layer "B.Cu")
		(at 190.367158 -13.60043 -90)
		(property "Reference" "R593"
			(at 0 0 90)
			(layer "B.SilkS")
			(hide yes)
			(effects
				(font
					(size 1.27 1.27)
				)
				(justify mirror)
			)
		)
		(property "Value" ""
			(at 0 0 90)
			(layer "B.Fab")
			(effects
				(font
					(size 1.27 1.27)
				)
				(justify mirror)
			)
		)
		(duplicate_pad_numbers_are_jumpers no)
		(fp_line
			(start -0.7874 0.4064)
			(end 0.7874 0.4064)
			(stroke
				(width 0.1524)
				(type default)
			)
			(layer "B.SilkS")
		)
		(fp_line
			(start 0.7874 0.4064)
			(end 0.7874 -0.4064)
			(stroke
				(width 0.1524)
				(type default)
			)
			(layer "B.SilkS")
		)
		(fp_line
			(start -0.7874 -0.4064)
			(end -0.7874 0.4064)
			(stroke
				(width 0.1524)
				(type default)
			)
			(layer "B.SilkS")
		)
		(fp_line
			(start 0.7874 -0.4064)
			(end -0.7874 -0.4064)
			(stroke
				(width 0.1524)
				(type default)
			)
			(layer "B.SilkS")
		)
		(fp_line
			(start -0.67945 0.3048)
			(end -0.120396 0.3048)
			(stroke
				(width 0.1)
				(type default)
			)
			(layer "B.Fab")
		)
		(fp_line
			(start -0.120396 0.3048)
			(end -0.120396 0.2794)
			(stroke
				(width 0.1)
				(type default)
			)
			(layer "B.Fab")
		)
		(fp_line
			(start 0.12065 0.3048)
			(end 0.67945 0.3048)
			(stroke
				(width 0.1)
				(type default)
			)
			(layer "B.Fab")
		)
		(fp_line
			(start 0.67945 0.3048)
			(end 0.67945 -0.305054)
			(stroke
				(width 0.1)
				(type default)
			)
			(layer "B.Fab")
		)
		(fp_line
			(start -0.120396 0.2794)
			(end 0.12065 0.2794)
			(stroke
				(width 0.1)
				(type default)
			)
			(layer "B.Fab")
		)
		(fp_line
			(start 0.12065 0.2794)
			(end 0.12065 0.3048)
			(stroke
				(width 0.1)
				(type default)
			)
			(layer "B.Fab")
		)
		(fp_line
			(start -0.12065 -0.2794)
			(end -0.12065 -0.3048)
			(stroke
				(width 0.1)
				(type default)
			)
			(layer "B.Fab")
		)
		(fp_line
			(start 0.12065 -0.2794)
			(end -0.12065 -0.2794)
			(stroke
				(width 0.1)
				(type default)
			)
			(layer "B.Fab")
		)
		(fp_line
			(start -0.67945 -0.3048)
			(end -0.67945 0.3048)
			(stroke
				(width 0.1)
				(type default)
			)
			(layer "B.Fab")
		)
		(fp_line
			(start -0.12065 -0.3048)
			(end -0.67945 -0.3048)
			(stroke
				(width 0.1)
				(type default)
			)
			(layer "B.Fab")
		)
		(fp_line
			(start 0.12065 -0.305054)
			(end 0.12065 -0.2794)
			(stroke
				(width 0.1)
				(type default)
			)
			(layer "B.Fab")
		)
		(fp_line
			(start 0.67945 -0.305054)
			(end 0.12065 -0.305054)
			(stroke
				(width 0.1)
				(type default)
			)
			(layer "B.Fab")
		)
		(pad "1" smd circle
			(at 0.40005 0 90)
			(size 0 0)
			(layers "B.Cu" "B.Mask" "B.Paste")
			(net "I3C_SPD_DDRABCD_CPU0_BMC_R_SCL")
		)
		(pad "2" smd circle
			(at -0.40005 0 90)
			(size 0 0)
			(layers "B.Cu" "B.Mask" "B.Paste")
			(net "I3C_SPD_DDRABCD_CPU0_BMC_SCL")
		)
	)
)
